FILE_TYPE = CONNECTIVITY;
{Allegro Design Entry HDL 17.2-2016 S081 (4005846) 1/11/2022}
"PAGE_NUMBER" = 4;
0"NC";
END.
